(kicad_pcb
	(version 20260206)
	(generator "pcbnew")
	(generator_version "10.0")
	(general
		(thickness 1.6)
		(legacy_teardrops no)
	)
	(paper "A4")
	(title_block
		(title "riser — 13919-sa.brd")
		(comment 1 "Honey Badger (Wiwynn) / footprint 1 of 2 (GF2), pads 1-112 of 164")
	)
	(layers
		(0 "F.Cu" signal "TOP")
		(4 "In1.Cu" signal "L2VCC")
		(6 "In2.Cu" signal "L3GND")
		(2 "B.Cu" signal "BOTTOM")
		(9 "F.Adhes" user "F.Adhesive")
		(11 "B.Adhes" user "B.Adhesive")
		(13 "F.Paste" user "Package Geometry/Pastemask Top")
		(15 "B.Paste" user "Package Geometry/Pastemask Bottom")
		(5 "F.SilkS" user "Ref Des/Silkscreen Top")
		(7 "B.SilkS" user "Ref Des/Silkscreen Bottom")
		(1 "F.Mask" user "Board Geometry/Soldermask Top")
		(3 "B.Mask" user "Board Geometry/Soldermask Bottom")
		(17 "Dwgs.User" user "User.Drawings")
		(19 "Cmts.User" user "User.Comments")
		(21 "Eco1.User" user "User.Eco1")
		(23 "Eco2.User" user "User.Eco2")
		(25 "Edge.Cuts" user "Board Geometry/Outline")
		(27 "Margin" user)
		(31 "F.CrtYd" user "Package Geometry/Place Bound Top")
		(29 "B.CrtYd" user "Package Geometry/Place Bound Bottom")
		(35 "F.Fab" user "Ref Des/Assembly Top")
		(33 "B.Fab" user "Ref Des/Assembly Bottom")
	)
	(footprint ""
		(layer "F.Cu")
		(at 77.499972 -1.400048)
		(property "Reference" "GF2"
			(at 0 0 0)
			(layer "F.SilkS")
			(hide yes)
			(effects
				(font
					(size 1.27 1.27)
				)
			)
		)
		(property "Value" "GF-PCIE-164P-4-GP"
			(at -70.358 -9.0932 0)
			(unlocked yes)
			(layer "F.Fab")
			(hide yes)
			(effects
				(font
					(size 1.016 1.016)
					(thickness 0.1524)
				)
			)
		)
		(property "Device Type" "GF-PCIE-164P-4"
			(at -70.358 -10.6172 0)
			(unlocked yes)
			(layer "F.Fab")
			(hide yes)
			(effects
				(font
					(size 1.016 1.016)
					(thickness 0.1524)
				)
			)
		)
		(duplicate_pad_numbers_are_jumpers no)
		(pad "A1" smd rect
			(at 11.500104 -2.5908)
			(size 0.7112 3.2004)
			(layers "F.Cu" "F.Mask" "F.Paste")
			(net "BOARD_PRSNT#")
		)
		(pad "A2" smd rect
			(at 10.500106 -2.0955)
			(size 0.7112 4.191)
			(layers "F.Cu" "F.Mask" "F.Paste")
			(net "P12V")
		)
		(pad "A3" smd rect
			(at 9.500108 -2.0955)
			(size 0.7112 4.191)
			(layers "F.Cu" "F.Mask" "F.Paste")
			(net "P12V")
		)
		(pad "A4" smd rect
			(at 8.50011 -2.0955)
			(size 0.7112 4.191)
			(layers "F.Cu" "F.Mask" "F.Paste")
			(net "GND")
		)
		(pad "A5" smd rect
			(at 7.500112 -2.0955)
			(size 0.7112 4.191)
			(layers "F.Cu" "F.Mask" "F.Paste")
			(net "SLOT_ID0")
		)
		(pad "A6" smd rect
			(at 6.500114 -2.0955)
			(size 0.7112 4.191)
			(layers "F.Cu" "F.Mask" "F.Paste")
			(net "SLOT_ID1")
		)
		(pad "A7" smd rect
			(at 5.500116 -2.0955)
			(size 0.7112 4.191)
			(layers "F.Cu" "F.Mask" "F.Paste")
			(net "CPU_TXD")
		)
		(pad "A8" smd rect
			(at 4.500118 -2.0955)
			(size 0.7112 4.191)
			(layers "F.Cu" "F.Mask" "F.Paste")
			(net "CPU_RXD")
		)
		(pad "A9" smd rect
			(at 3.50012 -2.0955)
			(size 0.7112 4.191)
			(layers "F.Cu" "F.Mask" "F.Paste")
			(net "SLOT_ID2")
		)
		(pad "A10" smd rect
			(at 2.500122 -2.0955)
			(size 0.7112 4.191)
			(layers "F.Cu" "F.Mask" "F.Paste")
			(net "SLOT_ID3")
		)
		(pad "A11" smd rect
			(at 1.500124 -2.0955)
			(size 0.7112 4.191)
			(layers "F.Cu" "F.Mask" "F.Paste")
			(net "PCIE_RESET#")
		)
		(pad "A12" smd rect
			(at -1.500124 -2.0955)
			(size 0.7112 4.191)
			(layers "F.Cu" "F.Mask" "F.Paste")
			(net "GND")
		)
		(pad "A13" smd rect
			(at -2.500122 -2.0955)
			(size 0.7112 4.191)
			(layers "F.Cu" "F.Mask" "F.Paste")
			(net "CLK_100M_PCIE_SAS_C_P")
		)
		(pad "A14" smd rect
			(at -3.50012 -2.0955)
			(size 0.7112 4.191)
			(layers "F.Cu" "F.Mask" "F.Paste")
			(net "CLK_100M_PCIE_SAS_C_N")
		)
		(pad "A15" smd rect
			(at -4.500118 -2.0955)
			(size 0.7112 4.191)
			(layers "F.Cu" "F.Mask" "F.Paste")
			(net "GND")
		)
		(pad "A16" smd rect
			(at -5.500116 -2.0955)
			(size 0.7112 4.191)
			(layers "F.Cu" "F.Mask" "F.Paste")
			(net "GND")
		)
		(pad "A17" smd rect
			(at -6.500114 -2.0955)
			(size 0.7112 4.191)
			(layers "F.Cu" "F.Mask" "F.Paste")
			(net "P2E_CPU_SAS_RX_DP0")
		)
		(pad "A18" smd rect
			(at -7.500112 -2.0955)
			(size 0.7112 4.191)
			(layers "F.Cu" "F.Mask" "F.Paste")
			(net "P2E_CPU_SAS_RX_DN0")
		)
		(pad "A19" smd rect
			(at -8.50011 -2.0955)
			(size 0.7112 4.191)
			(layers "F.Cu" "F.Mask" "F.Paste")
			(net "GND")
		)
		(pad "A20" smd rect
			(at -9.500108 -2.0955)
			(size 0.7112 4.191)
			(layers "F.Cu" "F.Mask" "F.Paste")
			(net "GND")
		)
		(pad "A21" smd rect
			(at -10.500106 -2.0955)
			(size 0.7112 4.191)
			(layers "F.Cu" "F.Mask" "F.Paste")
			(net "P2E_CPU_SAS_RX_DP1")
		)
		(pad "A22" smd rect
			(at -11.500104 -2.0955)
			(size 0.7112 4.191)
			(layers "F.Cu" "F.Mask" "F.Paste")
			(net "P2E_CPU_SAS_RX_DN1")
		)
		(pad "A23" smd rect
			(at -12.500102 -2.0955)
			(size 0.7112 4.191)
			(layers "F.Cu" "F.Mask" "F.Paste")
			(net "GND")
		)
		(pad "A24" smd rect
			(at -13.5001 -2.0955)
			(size 0.7112 4.191)
			(layers "F.Cu" "F.Mask" "F.Paste")
			(net "GND")
		)
		(pad "A25" smd rect
			(at -14.500098 -2.0955)
			(size 0.7112 4.191)
			(layers "F.Cu" "F.Mask" "F.Paste")
			(net "P2E_CPU_SAS_RX_DP2")
		)
		(pad "A26" smd rect
			(at -15.500096 -2.0955)
			(size 0.7112 4.191)
			(layers "F.Cu" "F.Mask" "F.Paste")
			(net "P2E_CPU_SAS_RX_DN2")
		)
		(pad "A27" smd rect
			(at -16.500094 -2.0955)
			(size 0.7112 4.191)
			(layers "F.Cu" "F.Mask" "F.Paste")
			(net "GND")
		)
		(pad "A28" smd rect
			(at -17.500092 -2.0955)
			(size 0.7112 4.191)
			(layers "F.Cu" "F.Mask" "F.Paste")
			(net "GND")
		)
		(pad "A29" smd rect
			(at -18.50009 -2.0955)
			(size 0.7112 4.191)
			(layers "F.Cu" "F.Mask" "F.Paste")
			(net "P2E_CPU_SAS_RX_DP3")
		)
		(pad "A30" smd rect
			(at -19.500088 -2.0955)
			(size 0.7112 4.191)
			(layers "F.Cu" "F.Mask" "F.Paste")
			(net "P2E_CPU_SAS_RX_DN3")
		)
		(pad "A31" smd rect
			(at -20.500086 -2.0955)
			(size 0.7112 4.191)
			(layers "F.Cu" "F.Mask" "F.Paste")
			(net "GND")
		)
		(pad "A32" smd rect
			(at -21.500084 -2.0955)
			(size 0.7112 4.191)
			(layers "F.Cu" "F.Mask" "F.Paste")
			(net "GND")
		)
		(pad "A33" smd rect
			(at -22.500082 -2.0955)
			(size 0.7112 4.191)
			(layers "F.Cu" "F.Mask" "F.Paste")
			(net "SATA2_RX_C_DP0")
		)
		(pad "A34" smd rect
			(at -23.50008 -2.0955)
			(size 0.7112 4.191)
			(layers "F.Cu" "F.Mask" "F.Paste")
			(net "SATA2_RX_C_DN0")
		)
		(pad "A35" smd rect
			(at -24.500078 -2.0955)
			(size 0.7112 4.191)
			(layers "F.Cu" "F.Mask" "F.Paste")
			(net "GND")
		)
		(pad "A36" smd rect
			(at -25.500076 -2.0955)
			(size 0.7112 4.191)
			(layers "F.Cu" "F.Mask" "F.Paste")
			(net "GND")
		)
		(pad "A37" smd rect
			(at -26.500074 -2.0955)
			(size 0.7112 4.191)
			(layers "F.Cu" "F.Mask" "F.Paste")
			(net "PCIE_RSVD_A37")
		)
		(pad "A38" smd rect
			(at -27.500072 -2.0955)
			(size 0.7112 4.191)
			(layers "F.Cu" "F.Mask" "F.Paste")
			(net "PCIE_RSVD_A38")
		)
		(pad "A39" smd rect
			(at -28.50007 -2.0955)
			(size 0.7112 4.191)
			(layers "F.Cu" "F.Mask" "F.Paste")
			(net "GND")
		)
		(pad "A40" smd rect
			(at -29.500068 -2.0955)
			(size 0.7112 4.191)
			(layers "F.Cu" "F.Mask" "F.Paste")
			(net "GND")
		)
		(pad "A41" smd rect
			(at -30.500066 -2.0955)
			(size 0.7112 4.191)
			(layers "F.Cu" "F.Mask" "F.Paste")
			(net "PCIE_RSVD_A41")
		)
		(pad "A42" smd rect
			(at -31.500064 -2.0955)
			(size 0.7112 4.191)
			(layers "F.Cu" "F.Mask" "F.Paste")
			(net "GBE_SMBALRT_R#")
		)
		(pad "A43" smd rect
			(at -32.500062 -2.0955)
			(size 0.7112 4.191)
			(layers "F.Cu" "F.Mask" "F.Paste")
			(net "GND")
		)
		(pad "A44" smd rect
			(at -33.50006 -2.0955)
			(size 0.7112 4.191)
			(layers "F.Cu" "F.Mask" "F.Paste")
			(net "GND")
		)
		(pad "A45" smd rect
			(at -34.500058 -2.0955)
			(size 0.7112 4.191)
			(layers "F.Cu" "F.Mask" "F.Paste")
			(net "CPU_GBE_RX_C_DP0")
		)
		(pad "A46" smd rect
			(at -35.500056 -2.0955)
			(size 0.7112 4.191)
			(layers "F.Cu" "F.Mask" "F.Paste")
			(net "CPU_GBE_RX_C_DN0")
		)
		(pad "A47" smd rect
			(at -36.500054 -2.0955)
			(size 0.7112 4.191)
			(layers "F.Cu" "F.Mask" "F.Paste")
			(net "GND")
		)
		(pad "A48" smd rect
			(at -37.500052 -2.0955)
			(size 0.7112 4.191)
			(layers "F.Cu" "F.Mask" "F.Paste")
			(net "GND")
		)
		(pad "A49" smd rect
			(at -38.50005 -2.0955)
			(size 0.7112 4.191)
			(layers "F.Cu" "F.Mask" "F.Paste")
			(net "P2E_CPU_SAS_RX_DP4")
		)
		(pad "A50" smd rect
			(at -39.500048 -2.0955)
			(size 0.7112 4.191)
			(layers "F.Cu" "F.Mask" "F.Paste")
			(net "P2E_CPU_SAS_RX_DN4")
		)
		(pad "A51" smd rect
			(at -40.500046 -2.0955)
			(size 0.7112 4.191)
			(layers "F.Cu" "F.Mask" "F.Paste")
			(net "GND")
		)
		(pad "A52" smd rect
			(at -41.500044 -2.0955)
			(size 0.7112 4.191)
			(layers "F.Cu" "F.Mask" "F.Paste")
			(net "GND")
		)
		(pad "A53" smd rect
			(at -42.500042 -2.0955)
			(size 0.7112 4.191)
			(layers "F.Cu" "F.Mask" "F.Paste")
			(net "P2E_CPU_SAS_RX_DP5")
		)
		(pad "A54" smd rect
			(at -43.50004 -2.0955)
			(size 0.7112 4.191)
			(layers "F.Cu" "F.Mask" "F.Paste")
			(net "P2E_CPU_SAS_RX_DN5")
		)
		(pad "A55" smd rect
			(at -44.500038 -2.0955)
			(size 0.7112 4.191)
			(layers "F.Cu" "F.Mask" "F.Paste")
			(net "GND")
		)
		(pad "A56" smd rect
			(at -45.500036 -2.0955)
			(size 0.7112 4.191)
			(layers "F.Cu" "F.Mask" "F.Paste")
			(net "GND")
		)
		(pad "A57" smd rect
			(at -46.500034 -2.0955)
			(size 0.7112 4.191)
			(layers "F.Cu" "F.Mask" "F.Paste")
			(net "P2E_CPU_SAS_RX_DP6")
		)
		(pad "A58" smd rect
			(at -47.500032 -2.0955)
			(size 0.7112 4.191)
			(layers "F.Cu" "F.Mask" "F.Paste")
			(net "P2E_CPU_SAS_RX_DN6")
		)
		(pad "A59" smd rect
			(at -48.50003 -2.0955)
			(size 0.7112 4.191)
			(layers "F.Cu" "F.Mask" "F.Paste")
			(net "GND")
		)
		(pad "A60" smd rect
			(at -49.500028 -2.0955)
			(size 0.7112 4.191)
			(layers "F.Cu" "F.Mask" "F.Paste")
			(net "GND")
		)
		(pad "A61" smd rect
			(at -50.500026 -2.0955)
			(size 0.7112 4.191)
			(layers "F.Cu" "F.Mask" "F.Paste")
			(net "P2E_CPU_SAS_RX_DP7")
		)
		(pad "A62" smd rect
			(at -51.500024 -2.0955)
			(size 0.7112 4.191)
			(layers "F.Cu" "F.Mask" "F.Paste")
			(net "P2E_CPU_SAS_RX_DN7")
		)
		(pad "A63" smd rect
			(at -52.500022 -2.0955)
			(size 0.7112 4.191)
			(layers "F.Cu" "F.Mask" "F.Paste")
			(net "GND")
		)
		(pad "A64" smd rect
			(at -53.50002 -2.0955)
			(size 0.7112 4.191)
			(layers "F.Cu" "F.Mask" "F.Paste")
			(net "GND")
		)
		(pad "A65" smd rect
			(at -54.500018 -2.0955)
			(size 0.7112 4.191)
			(layers "F.Cu" "F.Mask" "F.Paste")
			(net "P2E_CPU_ETH10G_RX_DP8")
		)
		(pad "A66" smd rect
			(at -55.500016 -2.0955)
			(size 0.7112 4.191)
			(layers "F.Cu" "F.Mask" "F.Paste")
			(net "P2E_CPU_ETH10G_RX_DN8")
		)
		(pad "A67" smd rect
			(at -56.500014 -2.0955)
			(size 0.7112 4.191)
			(layers "F.Cu" "F.Mask" "F.Paste")
			(net "GND")
		)
		(pad "A68" smd rect
			(at -57.500012 -2.0955)
			(size 0.7112 4.191)
			(layers "F.Cu" "F.Mask" "F.Paste")
			(net "GND")
		)
		(pad "A69" smd rect
			(at -58.50001 -2.0955)
			(size 0.7112 4.191)
			(layers "F.Cu" "F.Mask" "F.Paste")
			(net "P2E_CPU_ETH10G_RX_DP9")
		)
		(pad "A70" smd rect
			(at -59.500008 -2.0955)
			(size 0.7112 4.191)
			(layers "F.Cu" "F.Mask" "F.Paste")
			(net "P2E_CPU_ETH10G_RX_DN9")
		)
		(pad "A71" smd rect
			(at -60.500006 -2.0955)
			(size 0.7112 4.191)
			(layers "F.Cu" "F.Mask" "F.Paste")
			(net "GND")
		)
		(pad "A72" smd rect
			(at -61.500004 -2.0955)
			(size 0.7112 4.191)
			(layers "F.Cu" "F.Mask" "F.Paste")
			(net "GND")
		)
		(pad "A73" smd rect
			(at -62.500002 -2.0955)
			(size 0.7112 4.191)
			(layers "F.Cu" "F.Mask" "F.Paste")
			(net "P2E_CPU_ETH10G_RX_DP10")
		)
		(pad "A74" smd rect
			(at -63.5 -2.0955)
			(size 0.7112 4.191)
			(layers "F.Cu" "F.Mask" "F.Paste")
			(net "P2E_CPU_ETH10G_RX_DN10")
		)
		(pad "A75" smd rect
			(at -64.499998 -2.0955)
			(size 0.7112 4.191)
			(layers "F.Cu" "F.Mask" "F.Paste")
			(net "GND")
		)
		(pad "A76" smd rect
			(at -65.499996 -2.0955)
			(size 0.7112 4.191)
			(layers "F.Cu" "F.Mask" "F.Paste")
			(net "GND")
		)
		(pad "A77" smd rect
			(at -66.499994 -2.0955)
			(size 0.7112 4.191)
			(layers "F.Cu" "F.Mask" "F.Paste")
			(net "P2E_CPU_ETH10G_RX_DP11")
		)
		(pad "A78" smd rect
			(at -67.499992 -2.0955)
			(size 0.7112 4.191)
			(layers "F.Cu" "F.Mask" "F.Paste")
			(net "P2E_CPU_ETH10G_RX_DN11")
		)
		(pad "A79" smd rect
			(at -68.49999 -2.0955)
			(size 0.7112 4.191)
			(layers "F.Cu" "F.Mask" "F.Paste")
			(net "GND")
		)
		(pad "A80" smd rect
			(at -69.499988 -2.0955)
			(size 0.7112 4.191)
			(layers "F.Cu" "F.Mask" "F.Paste")
			(net "GND")
		)
		(pad "A81" smd rect
			(at -70.499986 -2.0955)
			(size 0.7112 4.191)
			(layers "F.Cu" "F.Mask" "F.Paste")
			(net "P12V")
		)
		(pad "A82" smd rect
			(at -71.499984 -2.0955)
			(size 0.7112 4.191)
			(layers "F.Cu" "F.Mask" "F.Paste")
			(net "P12V")
		)
		(pad "B1" smd rect
			(at 11.500104 -1.7145)
			(size 0.7112 4.191)
			(drill
				(offset 0 -0.381)
			)
			(layers "F.Cu" "F.Mask" "F.Paste")
			(net "P12V")
		)
		(pad "B2" smd rect
			(at 10.500106 -1.7145)
			(size 0.7112 4.191)
			(drill
				(offset 0 -0.381)
			)
			(layers "F.Cu" "F.Mask" "F.Paste")
			(net "P12V")
		)
		(pad "B3" smd rect
			(at 9.500108 -1.7145)
			(size 0.7112 4.191)
			(drill
				(offset 0 -0.381)
			)
			(layers "F.Cu" "F.Mask" "F.Paste")
			(net "P12V")
		)
		(pad "B4" smd rect
			(at 8.50011 -1.7145)
			(size 0.7112 4.191)
			(drill
				(offset 0 -0.381)
			)
			(layers "F.Cu" "F.Mask" "F.Paste")
			(net "GND")
		)
		(pad "B5" smd rect
			(at 7.500112 -1.7145)
			(size 0.7112 4.191)
			(drill
				(offset 0 -0.381)
			)
			(layers "F.Cu" "F.Mask" "F.Paste")
			(net "BMC_I2C_CLK")
		)
		(pad "B6" smd rect
			(at 6.500114 -1.7145)
			(size 0.7112 4.191)
			(drill
				(offset 0 -0.381)
			)
			(layers "F.Cu" "F.Mask" "F.Paste")
			(net "BMC_I2C_DATA")
		)
		(pad "B7" smd rect
			(at 5.500116 -1.7145)
			(size 0.7112 4.191)
			(drill
				(offset 0 -0.381)
			)
			(layers "F.Cu" "F.Mask" "F.Paste")
			(net "GND")
		)
		(pad "B8" smd rect
			(at 4.500118 -1.7145)
			(size 0.7112 4.191)
			(drill
				(offset 0 -0.381)
			)
			(layers "F.Cu" "F.Mask" "F.Paste")
			(net "PMU_PWRBTN#")
		)
		(pad "B9" smd rect
			(at 3.50012 -1.7145)
			(size 0.7112 4.191)
			(drill
				(offset 0 -0.381)
			)
			(layers "F.Cu" "F.Mask" "F.Paste")
			(net "USB_P1_DP")
		)
		(pad "B10" smd rect
			(at 2.500122 -1.7145)
			(size 0.7112 4.191)
			(drill
				(offset 0 -0.381)
			)
			(layers "F.Cu" "F.Mask" "F.Paste")
			(net "USB_P1_DN")
		)
		(pad "B11" smd rect
			(at 1.500124 -1.7145)
			(size 0.7112 4.191)
			(drill
				(offset 0 -0.381)
			)
			(layers "F.Cu" "F.Mask" "F.Paste")
			(net "BMC_SYS_RESET#")
		)
		(pad "B12" smd rect
			(at -1.500124 -1.7145)
			(size 0.7112 4.191)
			(drill
				(offset 0 -0.381)
			)
			(layers "F.Cu" "F.Mask" "F.Paste")
			(net "BMC_I2C_ALERT#")
		)
		(pad "B13" smd rect
			(at -2.500122 -1.7145)
			(size 0.7112 4.191)
			(drill
				(offset 0 -0.381)
			)
			(layers "F.Cu" "F.Mask" "F.Paste")
			(net "GND")
		)
		(pad "B14" smd rect
			(at -3.50012 -1.7145)
			(size 0.7112 4.191)
			(drill
				(offset 0 -0.381)
			)
			(layers "F.Cu" "F.Mask" "F.Paste")
			(net "GND")
		)
		(pad "B15" smd rect
			(at -4.500118 -1.7145)
			(size 0.7112 4.191)
			(drill
				(offset 0 -0.381)
			)
			(layers "F.Cu" "F.Mask" "F.Paste")
			(net "P2E_CPU_SAS_TX_DP0")
		)
		(pad "B16" smd rect
			(at -5.500116 -1.7145)
			(size 0.7112 4.191)
			(drill
				(offset 0 -0.381)
			)
			(layers "F.Cu" "F.Mask" "F.Paste")
			(net "P2E_CPU_SAS_TX_DN0")
		)
		(pad "B17" smd rect
			(at -6.500114 -2.5908)
			(size 0.7112 3.2004)
			(layers "F.Cu" "F.Mask" "F.Paste")
			(net "GND")
		)
		(pad "B18" smd rect
			(at -7.500112 -1.7145)
			(size 0.7112 4.191)
			(drill
				(offset 0 -0.381)
			)
			(layers "F.Cu" "F.Mask" "F.Paste")
			(net "GND")
		)
		(pad "B19" smd rect
			(at -8.50011 -1.7145)
			(size 0.7112 4.191)
			(drill
				(offset 0 -0.381)
			)
			(layers "F.Cu" "F.Mask" "F.Paste")
			(net "P2E_CPU_SAS_TX_DP1")
		)
		(pad "B20" smd rect
			(at -9.500108 -1.7145)
			(size 0.7112 4.191)
			(drill
				(offset 0 -0.381)
			)
			(layers "F.Cu" "F.Mask" "F.Paste")
			(net "P2E_CPU_SAS_TX_DN1")
		)
		(pad "B21" smd rect
			(at -10.500106 -1.7145)
			(size 0.7112 4.191)
			(drill
				(offset 0 -0.381)
			)
			(layers "F.Cu" "F.Mask" "F.Paste")
			(net "GND")
		)
		(pad "B22" smd rect
			(at -11.500104 -1.7145)
			(size 0.7112 4.191)
			(drill
				(offset 0 -0.381)
			)
			(layers "F.Cu" "F.Mask" "F.Paste")
			(net "GND")
		)
		(pad "B23" smd rect
			(at -12.500102 -1.7145)
			(size 0.7112 4.191)
			(drill
				(offset 0 -0.381)
			)
			(layers "F.Cu" "F.Mask" "F.Paste")
			(net "P2E_CPU_SAS_TX_DP2")
		)
		(pad "B24" smd rect
			(at -13.5001 -1.7145)
			(size 0.7112 4.191)
			(drill
				(offset 0 -0.381)
			)
			(layers "F.Cu" "F.Mask" "F.Paste")
			(net "P2E_CPU_SAS_TX_DN2")
		)
		(pad "B25" smd rect
			(at -14.500098 -1.7145)
			(size 0.7112 4.191)
			(drill
				(offset 0 -0.381)
			)
			(layers "F.Cu" "F.Mask" "F.Paste")
			(net "GND")
		)
		(pad "B26" smd rect
			(at -15.500096 -1.7145)
			(size 0.7112 4.191)
			(drill
				(offset 0 -0.381)
			)
			(layers "F.Cu" "F.Mask" "F.Paste")
			(net "GND")
		)
		(pad "B27" smd rect
			(at -16.500094 -1.7145)
			(size 0.7112 4.191)
			(drill
				(offset 0 -0.381)
			)
			(layers "F.Cu" "F.Mask" "F.Paste")
			(net "P2E_CPU_SAS_TX_DP3")
		)
		(pad "B28" smd rect
			(at -17.500092 -1.7145)
			(size 0.7112 4.191)
			(drill
				(offset 0 -0.381)
			)
			(layers "F.Cu" "F.Mask" "F.Paste")
			(net "P2E_CPU_SAS_TX_DN3")
		)
		(pad "B29" smd rect
			(at -18.50009 -1.7145)
			(size 0.7112 4.191)
			(drill
				(offset 0 -0.381)
			)
			(layers "F.Cu" "F.Mask" "F.Paste")
			(net "GND")
		)
		(pad "B30" smd rect
			(at -19.500088 -1.7145)
			(size 0.7112 4.191)
			(drill
				(offset 0 -0.381)
			)
			(layers "F.Cu" "F.Mask" "F.Paste")
			(net "GND")
		)
	)
)
